(kicad_pcb
	(version 20260206)
	(generator "pcbnew")
	(generator_version "10.0")
	(general
		(thickness 1.6)
		(legacy_teardrops no)
	)
	(paper "A4")
	(title_block
		(title "04192023_DAF0TMB3IC0_F0TG_MB_C_brd_V02_OCP.brd")
		(comment 1 "Grand Teton / footprint 3955 of 8354 (U25), pads 2447-2558 of 6102")
	)
	(layers
		(0 "F.Cu" signal "TOP")
		(4 "In1.Cu" signal "GND")
		(6 "In2.Cu" signal "IN1")
		(8 "In3.Cu" signal "GND1")
		(10 "In4.Cu" signal "IN2")
		(12 "In5.Cu" signal "GND2")
		(14 "In6.Cu" signal "IN3")
		(16 "In7.Cu" signal "GND3")
		(18 "In8.Cu" signal "VCC")
		(20 "In9.Cu" signal "VCC1")
		(22 "In10.Cu" signal "GND4")
		(24 "In11.Cu" signal "IN4")
		(26 "In12.Cu" signal "GND5")
		(28 "In13.Cu" signal "IN5")
		(30 "In14.Cu" signal "GND6")
		(32 "In15.Cu" signal "IN6")
		(34 "In16.Cu" signal "GND7")
		(2 "B.Cu" signal "BOTTOM")
		(9 "F.Adhes" user "F.Adhesive")
		(11 "B.Adhes" user "B.Adhesive")
		(13 "F.Paste" user "Package Geometry/Pastemask Top")
		(15 "B.Paste" user "Package Geometry/Pastemask Bottom")
		(5 "F.SilkS" user "Ref Des/Silkscreen Top")
		(7 "B.SilkS" user "Ref Des/Silkscreen Bottom")
		(1 "F.Mask" user "Board Geometry/Soldermask Top")
		(3 "B.Mask" user "Board Geometry/Soldermask Bottom")
		(17 "Dwgs.User" user "User.Drawings")
		(19 "Cmts.User" user "User.Comments")
		(21 "Eco1.User" user "User.Eco1")
		(23 "Eco2.User" user "User.Eco2")
		(25 "Edge.Cuts" user "Board Geometry/Outline")
		(27 "Margin" user)
		(31 "F.CrtYd" user "Package Geometry/Place Bound Top")
		(29 "B.CrtYd" user "Package Geometry/Place Bound Bottom")
		(35 "F.Fab" user "Ref Des/Assembly Top")
		(33 "B.Fab" user "Ref Des/Assembly Bottom")
	)
	(footprint ""
		(layer "F.Cu")
		(at 359.867962 -258.880102 180)
		(property "Reference" "U25"
			(at -45.78477 -62.086744 0)
			(unlocked yes)
			(layer "F.SilkS")
			(effects
				(font
					(size 0.7874 0.5842)
					(thickness 0.1524)
				)
			)
		)
		(property "Value" ""
			(at 0 0 180)
			(layer "F.Fab")
			(effects
				(font
					(size 1.27 1.27)
				)
			)
		)
		(duplicate_pad_numbers_are_jumpers no)
		(pad "BT73" smd circle
			(at 32.749998 10.07999 180)
			(size 0.450088 0.450088)
			(layers "F.Cu" "F.Mask" "F.Paste")
			(net "GND")
		)
		(pad "BT74" smd circle
			(at 33.690052 10.07999 180)
			(size 0.450088 0.450088)
			(layers "F.Cu" "F.Mask" "F.Paste")
			(net "M_A_CPU0_SB_CB<4>")
		)
		(pad "BU1" smd circle
			(at -34.459926 10.889996 180)
			(size 0.450088 0.450088)
			(layers "F.Cu" "F.Mask" "F.Paste")
			(net "GND")
		)
		(pad "BU2" smd circle
			(at -33.519872 10.889996 180)
			(size 0.450088 0.450088)
			(layers "F.Cu" "F.Mask" "F.Paste")
			(net "M_G_CPU0_SB_CB<6>")
		)
		(pad "BU3" smd circle
			(at -32.580072 10.889996 180)
			(size 0.450088 0.450088)
			(layers "F.Cu" "F.Mask" "F.Paste")
			(net "M_G_CPU0_SB_CB<5>")
		)
		(pad "BU4" smd circle
			(at -31.640018 10.889996 180)
			(size 0.450088 0.450088)
			(layers "F.Cu" "F.Mask" "F.Paste")
			(net "GND")
		)
		(pad "BU5" smd circle
			(at -30.699964 10.889996 180)
			(size 0.450088 0.450088)
			(layers "F.Cu" "F.Mask" "F.Paste")
			(net "M_K_CPU0_SB_CB<6>")
		)
		(pad "BU6" smd circle
			(at -29.75991 10.889996 180)
			(size 0.450088 0.450088)
			(layers "F.Cu" "F.Mask" "F.Paste")
			(net "GND")
		)
		(pad "BU7" smd circle
			(at -28.82011 10.889996 180)
			(size 0.450088 0.450088)
			(layers "F.Cu" "F.Mask" "F.Paste")
			(net "M_K_CPU0_SB_CB<5>")
		)
		(pad "BU8" smd circle
			(at -27.880056 10.889996 180)
			(size 0.450088 0.450088)
			(layers "F.Cu" "F.Mask" "F.Paste")
			(net "GND")
		)
		(pad "BU9" smd circle
			(at -26.940002 10.889996 180)
			(size 0.450088 0.450088)
			(layers "F.Cu" "F.Mask" "F.Paste")
			(net "M_L_CPU0_SB_CB<6>")
		)
		(pad "BU10" smd circle
			(at -25.999948 10.889996 180)
			(size 0.450088 0.450088)
			(layers "F.Cu" "F.Mask" "F.Paste")
			(net "M_L_CPU0_SB_CB<5>")
		)
		(pad "BU11" smd circle
			(at -25.059894 10.889996 180)
			(size 0.450088 0.450088)
			(layers "F.Cu" "F.Mask" "F.Paste")
			(net "GND")
		)
		(pad "BU12" smd circle
			(at -24.120094 10.889996 180)
			(size 0.450088 0.450088)
			(layers "F.Cu" "F.Mask" "F.Paste")
			(net "M_H_CPU0_SB_CB<6>")
		)
		(pad "BU13" smd circle
			(at -23.18004 10.889996 180)
			(size 0.450088 0.450088)
			(layers "F.Cu" "F.Mask" "F.Paste")
			(net "GND")
		)
		(pad "BU14" smd circle
			(at -22.239986 10.889996 180)
			(size 0.450088 0.450088)
			(layers "F.Cu" "F.Mask" "F.Paste")
			(net "M_H_CPU0_SB_CB<5>")
		)
		(pad "BU15" smd circle
			(at -21.299932 10.889996 180)
			(size 0.450088 0.450088)
			(layers "F.Cu" "F.Mask" "F.Paste")
			(net "GND")
		)
		(pad "BU16" smd circle
			(at -20.359878 10.889996 180)
			(size 0.450088 0.450088)
			(layers "F.Cu" "F.Mask" "F.Paste")
			(net "M_J_CPU0_SB_CB<6>")
		)
		(pad "BU17" smd circle
			(at -19.420078 10.889996 180)
			(size 0.450088 0.450088)
			(layers "F.Cu" "F.Mask" "F.Paste")
			(net "M_J_CPU0_SB_CB<5>")
		)
		(pad "BU18" smd circle
			(at -18.480024 10.889996 180)
			(size 0.450088 0.450088)
			(layers "F.Cu" "F.Mask" "F.Paste")
			(net "GND")
		)
		(pad "BU19" smd circle
			(at -17.53997 10.889996 180)
			(size 0.450088 0.450088)
			(layers "F.Cu" "F.Mask" "F.Paste")
			(net "M_I_CPU0_SB_CB<6>")
		)
		(pad "BU20" smd circle
			(at -16.599916 10.889996 180)
			(size 0.450088 0.450088)
			(layers "F.Cu" "F.Mask" "F.Paste")
			(net "GND")
		)
		(pad "BU21" smd circle
			(at -15.660116 10.889996 180)
			(size 0.450088 0.450088)
			(layers "F.Cu" "F.Mask" "F.Paste")
			(net "M_I_CPU0_SB_CB<5>")
		)
		(pad "BU22" smd circle
			(at -14.720062 10.889996 180)
			(size 0.450088 0.450088)
			(layers "F.Cu" "F.Mask" "F.Paste")
			(net "GND")
		)
		(pad "BU23" smd circle
			(at -13.780008 10.889996 180)
			(size 0.450088 0.450088)
			(layers "F.Cu" "F.Mask" "F.Paste")
			(net "P5E_CPU0_P2_TX_DN<13>")
		)
		(pad "BU24" smd circle
			(at -12.839954 10.889996 180)
			(size 0.450088 0.450088)
			(layers "F.Cu" "F.Mask" "F.Paste")
			(net "P5E_CPU0_P2_TX_DP<13>")
		)
		(pad "BU25" smd circle
			(at -11.8999 10.889996 180)
			(size 0.450088 0.450088)
			(layers "F.Cu" "F.Mask" "F.Paste")
			(net "GND")
		)
		(pad "BU26" smd circle
			(at -10.9601 10.889996 180)
			(size 0.450088 0.450088)
			(layers "F.Cu" "F.Mask" "F.Paste")
			(net "P5E_CPU0_P2_TX_DN<10>")
		)
		(pad "BU27" smd circle
			(at -10.020046 10.889996 180)
			(size 0.450088 0.450088)
			(layers "F.Cu" "F.Mask" "F.Paste")
			(net "P5E_CPU0_P2_TX_DP<10>")
		)
		(pad "BU28" smd circle
			(at -9.079992 10.889996 180)
			(size 0.450088 0.450088)
			(layers "F.Cu" "F.Mask" "F.Paste")
			(net "GND")
		)
		(pad "BU29" smd circle
			(at -8.139938 10.889996 180)
			(size 0.450088 0.450088)
			(layers "F.Cu" "F.Mask" "F.Paste")
			(net "P5E_CPU0_P2_TX_DN<7>")
		)
		(pad "BU30" smd circle
			(at -7.199884 10.889996 180)
			(size 0.450088 0.450088)
			(layers "F.Cu" "F.Mask" "F.Paste")
			(net "P5E_CPU0_P2_TX_DP<7>")
		)
		(pad "BU31" smd circle
			(at -6.260084 10.889996 180)
			(size 0.450088 0.450088)
			(layers "F.Cu" "F.Mask" "F.Paste")
			(net "GND")
		)
		(pad "BU32" smd circle
			(at -5.32003 10.889996 180)
			(size 0.450088 0.450088)
			(layers "F.Cu" "F.Mask" "F.Paste")
			(net "P5E_CPU0_P2_TX_DN<4>")
		)
		(pad "BU33" smd circle
			(at -4.379976 10.889996 180)
			(size 0.450088 0.450088)
			(layers "F.Cu" "F.Mask" "F.Paste")
			(net "P5E_CPU0_P2_TX_DP<4>")
		)
		(pad "BU34" smd circle
			(at -3.439922 10.889996 180)
			(size 0.450088 0.450088)
			(layers "F.Cu" "F.Mask" "F.Paste")
			(net "GND")
		)
		(pad "BU35" smd circle
			(at -2.500122 10.889996 180)
			(size 0.450088 0.450088)
			(layers "F.Cu" "F.Mask" "F.Paste")
			(net "GND")
		)
		(pad "BU36" smd circle
			(at -1.560068 10.889996 180)
			(size 0.450088 0.450088)
			(layers "F.Cu" "F.Mask" "F.Paste")
			(net "GND")
		)
		(pad "BU40" smd circle
			(at 1.260094 10.889996 180)
			(size 0.450088 0.450088)
			(layers "F.Cu" "F.Mask" "F.Paste")
			(net "GND")
		)
		(pad "BU41" smd circle
			(at 2.199894 10.889996 180)
			(size 0.450088 0.450088)
			(layers "F.Cu" "F.Mask" "F.Paste")
			(net "GND")
		)
		(pad "BU42" smd circle
			(at 3.139948 10.889996 180)
			(size 0.450088 0.450088)
			(layers "F.Cu" "F.Mask" "F.Paste")
			(net "GND")
		)
		(pad "BU43" smd circle
			(at 4.080002 10.889996 180)
			(size 0.450088 0.450088)
			(layers "F.Cu" "F.Mask" "F.Paste")
			(net "P5E_CPU0_P0_RX_DP<11>")
		)
		(pad "BU44" smd circle
			(at 5.020056 10.889996 180)
			(size 0.450088 0.450088)
			(layers "F.Cu" "F.Mask" "F.Paste")
			(net "P5E_CPU0_P0_RX_DN<11>")
		)
		(pad "BU45" smd circle
			(at 5.96011 10.889996 180)
			(size 0.450088 0.450088)
			(layers "F.Cu" "F.Mask" "F.Paste")
			(net "GND")
		)
		(pad "BU46" smd circle
			(at 6.89991 10.889996 180)
			(size 0.450088 0.450088)
			(layers "F.Cu" "F.Mask" "F.Paste")
			(net "P5E_CPU0_P0_RX_DP<8>")
		)
		(pad "BU47" smd circle
			(at 7.839964 10.889996 180)
			(size 0.450088 0.450088)
			(layers "F.Cu" "F.Mask" "F.Paste")
			(net "P5E_CPU0_P0_RX_DN<8>")
		)
		(pad "BU48" smd circle
			(at 8.780018 10.889996 180)
			(size 0.450088 0.450088)
			(layers "F.Cu" "F.Mask" "F.Paste")
			(net "GND")
		)
		(pad "BU49" smd circle
			(at 9.720072 10.889996 180)
			(size 0.450088 0.450088)
			(layers "F.Cu" "F.Mask" "F.Paste")
			(net "P5E_CPU0_P0_RX_DP<5>")
		)
		(pad "BU50" smd circle
			(at 10.659872 10.889996 180)
			(size 0.450088 0.450088)
			(layers "F.Cu" "F.Mask" "F.Paste")
			(net "P5E_CPU0_P0_RX_DN<5>")
		)
		(pad "BU51" smd circle
			(at 11.599926 10.889996 180)
			(size 0.450088 0.450088)
			(layers "F.Cu" "F.Mask" "F.Paste")
			(net "GND")
		)
		(pad "BU52" smd circle
			(at 12.53998 10.889996 180)
			(size 0.450088 0.450088)
			(layers "F.Cu" "F.Mask" "F.Paste")
			(net "P5E_CPU0_P0_RX_DP<2>")
		)
		(pad "BU53" smd circle
			(at 13.480034 10.889996 180)
			(size 0.450088 0.450088)
			(layers "F.Cu" "F.Mask" "F.Paste")
			(net "P5E_CPU0_P0_RX_DN<2>")
		)
		(pad "BU54" smd circle
			(at 14.420088 10.889996 180)
			(size 0.450088 0.450088)
			(layers "F.Cu" "F.Mask" "F.Paste")
			(net "GND")
		)
		(pad "BU55" smd circle
			(at 15.359888 10.889996 180)
			(size 0.450088 0.450088)
			(layers "F.Cu" "F.Mask" "F.Paste")
			(net "M_C_CPU0_SB_CB<5>")
		)
		(pad "BU56" smd circle
			(at 16.299942 10.889996 180)
			(size 0.450088 0.450088)
			(layers "F.Cu" "F.Mask" "F.Paste")
			(net "GND")
		)
		(pad "BU57" smd circle
			(at 17.239996 10.889996 180)
			(size 0.450088 0.450088)
			(layers "F.Cu" "F.Mask" "F.Paste")
			(net "M_C_CPU0_SB_CB<6>")
		)
		(pad "BU58" smd circle
			(at 18.18005 10.889996 180)
			(size 0.450088 0.450088)
			(layers "F.Cu" "F.Mask" "F.Paste")
			(net "GND")
		)
		(pad "BU59" smd circle
			(at 19.120104 10.889996 180)
			(size 0.450088 0.450088)
			(layers "F.Cu" "F.Mask" "F.Paste")
			(net "M_D_CPU0_SB_CB<5>")
		)
		(pad "BU60" smd circle
			(at 20.059904 10.889996 180)
			(size 0.450088 0.450088)
			(layers "F.Cu" "F.Mask" "F.Paste")
			(net "M_D_CPU0_SB_CB<6>")
		)
		(pad "BU61" smd circle
			(at 20.999958 10.889996 180)
			(size 0.450088 0.450088)
			(layers "F.Cu" "F.Mask" "F.Paste")
			(net "GND")
		)
		(pad "BU62" smd circle
			(at 21.940012 10.889996 180)
			(size 0.450088 0.450088)
			(layers "F.Cu" "F.Mask" "F.Paste")
			(net "M_B_CPU0_SB_CB<5>")
		)
		(pad "BU63" smd circle
			(at 22.880066 10.889996 180)
			(size 0.450088 0.450088)
			(layers "F.Cu" "F.Mask" "F.Paste")
			(net "GND")
		)
		(pad "BU64" smd circle
			(at 23.82012 10.889996 180)
			(size 0.450088 0.450088)
			(layers "F.Cu" "F.Mask" "F.Paste")
			(net "M_B_CPU0_SB_CB<6>")
		)
		(pad "BU65" smd circle
			(at 24.75992 10.889996 180)
			(size 0.450088 0.450088)
			(layers "F.Cu" "F.Mask" "F.Paste")
			(net "GND")
		)
		(pad "BU66" smd circle
			(at 25.699974 10.889996 180)
			(size 0.450088 0.450088)
			(layers "F.Cu" "F.Mask" "F.Paste")
			(net "M_F_CPU0_SB_CB<5>")
		)
		(pad "BU67" smd circle
			(at 26.640028 10.889996 180)
			(size 0.450088 0.450088)
			(layers "F.Cu" "F.Mask" "F.Paste")
			(net "M_F_CPU0_SB_CB<6>")
		)
		(pad "BU68" smd circle
			(at 27.580082 10.889996 180)
			(size 0.450088 0.450088)
			(layers "F.Cu" "F.Mask" "F.Paste")
			(net "GND")
		)
		(pad "BU69" smd circle
			(at 28.519882 10.889996 180)
			(size 0.450088 0.450088)
			(layers "F.Cu" "F.Mask" "F.Paste")
			(net "M_E_CPU0_SB_CB<5>")
		)
		(pad "BU70" smd circle
			(at 29.459936 10.889996 180)
			(size 0.450088 0.450088)
			(layers "F.Cu" "F.Mask" "F.Paste")
			(net "GND")
		)
		(pad "BU71" smd circle
			(at 30.39999 10.889996 180)
			(size 0.450088 0.450088)
			(layers "F.Cu" "F.Mask" "F.Paste")
			(net "M_E_CPU0_SB_CB<6>")
		)
		(pad "BU72" smd circle
			(at 31.340044 10.889996 180)
			(size 0.450088 0.450088)
			(layers "F.Cu" "F.Mask" "F.Paste")
			(net "GND")
		)
		(pad "BU73" smd circle
			(at 32.280098 10.889996 180)
			(size 0.450088 0.450088)
			(layers "F.Cu" "F.Mask" "F.Paste")
			(net "M_A_CPU0_SB_CB<5>")
		)
		(pad "BU74" smd circle
			(at 33.219898 10.889996 180)
			(size 0.450088 0.450088)
			(layers "F.Cu" "F.Mask" "F.Paste")
			(net "M_A_CPU0_SB_CB<6>")
		)
		(pad "BU75" smd circle
			(at 34.159952 10.889996 180)
			(size 0.450088 0.450088)
			(layers "F.Cu" "F.Mask" "F.Paste")
			(net "GND")
		)
		(pad "BV2" smd circle
			(at -33.990026 11.700002 180)
			(size 0.450088 0.450088)
			(layers "F.Cu" "F.Mask" "F.Paste")
			(net "M_G_CPU0_SB_DQS_DP<9>")
		)
		(pad "BV3" smd circle
			(at -33.049972 11.700002 180)
			(size 0.450088 0.450088)
			(layers "F.Cu" "F.Mask" "F.Paste")
			(net "GND")
		)
		(pad "BV4" smd circle
			(at -32.109918 11.700002 180)
			(size 0.450088 0.450088)
			(layers "F.Cu" "F.Mask" "F.Paste")
			(net "M_G_CPU0_SB_CB<7>")
		)
		(pad "BV5" smd circle
			(at -31.170118 11.700002 180)
			(size 0.450088 0.450088)
			(layers "F.Cu" "F.Mask" "F.Paste")
			(net "PVDD11_S3_P0")
		)
		(pad "BV6" smd circle
			(at -30.230064 11.700002 180)
			(size 0.450088 0.450088)
			(layers "F.Cu" "F.Mask" "F.Paste")
			(net "M_K_CPU0_SB_DQS_DP<9>")
		)
		(pad "BV7" smd circle
			(at -29.29001 11.700002 180)
			(size 0.450088 0.450088)
			(layers "F.Cu" "F.Mask" "F.Paste")
			(net "M_K_CPU0_SB_CB<7>")
		)
		(pad "BV8" smd circle
			(at -28.349956 11.700002 180)
			(size 0.450088 0.450088)
			(layers "F.Cu" "F.Mask" "F.Paste")
			(net "GND")
		)
		(pad "BV9" smd circle
			(at -27.409902 11.700002 180)
			(size 0.450088 0.450088)
			(layers "F.Cu" "F.Mask" "F.Paste")
			(net "M_L_CPU0_SB_DQS_DP<9>")
		)
		(pad "BV10" smd circle
			(at -26.470102 11.700002 180)
			(size 0.450088 0.450088)
			(layers "F.Cu" "F.Mask" "F.Paste")
			(net "GND")
		)
		(pad "BV11" smd circle
			(at -25.530048 11.700002 180)
			(size 0.450088 0.450088)
			(layers "F.Cu" "F.Mask" "F.Paste")
			(net "M_L_CPU0_SB_CB<7>")
		)
		(pad "BV12" smd circle
			(at -24.589994 11.700002 180)
			(size 0.450088 0.450088)
			(layers "F.Cu" "F.Mask" "F.Paste")
			(net "PVDD11_S3_P0")
		)
		(pad "BV13" smd circle
			(at -23.64994 11.700002 180)
			(size 0.450088 0.450088)
			(layers "F.Cu" "F.Mask" "F.Paste")
			(net "M_H_CPU0_SB_DQS_DP<9>")
		)
		(pad "BV14" smd circle
			(at -22.709886 11.700002 180)
			(size 0.450088 0.450088)
			(layers "F.Cu" "F.Mask" "F.Paste")
			(net "M_H_CPU0_SB_CB<7>")
		)
		(pad "BV15" smd circle
			(at -21.770086 11.700002 180)
			(size 0.450088 0.450088)
			(layers "F.Cu" "F.Mask" "F.Paste")
			(net "GND")
		)
		(pad "BV16" smd circle
			(at -20.830032 11.700002 180)
			(size 0.450088 0.450088)
			(layers "F.Cu" "F.Mask" "F.Paste")
			(net "M_J_CPU0_SB_DQS_DP<9>")
		)
		(pad "BV17" smd circle
			(at -19.889978 11.700002 180)
			(size 0.450088 0.450088)
			(layers "F.Cu" "F.Mask" "F.Paste")
			(net "GND")
		)
		(pad "BV18" smd circle
			(at -18.949924 11.700002 180)
			(size 0.450088 0.450088)
			(layers "F.Cu" "F.Mask" "F.Paste")
			(net "M_J_CPU0_SB_CB<7>")
		)
		(pad "BV19" smd circle
			(at -18.010124 11.700002 180)
			(size 0.450088 0.450088)
			(layers "F.Cu" "F.Mask" "F.Paste")
			(net "PVDD11_S3_P0")
		)
		(pad "BV20" smd circle
			(at -17.07007 11.700002 180)
			(size 0.450088 0.450088)
			(layers "F.Cu" "F.Mask" "F.Paste")
			(net "M_I_CPU0_SB_DQS_DP<9>")
		)
		(pad "BV21" smd circle
			(at -16.130016 11.700002 180)
			(size 0.450088 0.450088)
			(layers "F.Cu" "F.Mask" "F.Paste")
			(net "M_I_CPU0_SB_CB<7>")
		)
		(pad "BV22" smd circle
			(at -15.189962 11.700002 180)
			(size 0.450088 0.450088)
			(layers "F.Cu" "F.Mask" "F.Paste")
			(net "PVDD11_S3_P0")
		)
		(pad "BV23" smd circle
			(at -14.249908 11.700002 180)
			(size 0.450088 0.450088)
			(layers "F.Cu" "F.Mask" "F.Paste")
			(net "GND")
		)
		(pad "BV24" smd circle
			(at -13.310108 11.700002 180)
			(size 0.450088 0.450088)
			(layers "F.Cu" "F.Mask" "F.Paste")
			(net "GND")
		)
		(pad "BV25" smd circle
			(at -12.370054 11.700002 180)
			(size 0.450088 0.450088)
			(layers "F.Cu" "F.Mask" "F.Paste")
			(net "GND")
		)
		(pad "BV26" smd circle
			(at -11.43 11.700002 180)
			(size 0.450088 0.450088)
			(layers "F.Cu" "F.Mask" "F.Paste")
			(net "GND")
		)
		(pad "BV27" smd circle
			(at -10.489946 11.700002 180)
			(size 0.450088 0.450088)
			(layers "F.Cu" "F.Mask" "F.Paste")
			(net "GND")
		)
		(pad "BV28" smd circle
			(at -9.549892 11.700002 180)
			(size 0.450088 0.450088)
			(layers "F.Cu" "F.Mask" "F.Paste")
			(net "GND")
		)
		(pad "BV29" smd circle
			(at -8.610092 11.700002 180)
			(size 0.450088 0.450088)
			(layers "F.Cu" "F.Mask" "F.Paste")
			(net "GND")
		)
		(pad "BV30" smd circle
			(at -7.670038 11.700002 180)
			(size 0.450088 0.450088)
			(layers "F.Cu" "F.Mask" "F.Paste")
			(net "GND")
		)
		(pad "BV31" smd circle
			(at -6.729984 11.700002 180)
			(size 0.450088 0.450088)
			(layers "F.Cu" "F.Mask" "F.Paste")
			(net "GND")
		)
		(pad "BV32" smd circle
			(at -5.78993 11.700002 180)
			(size 0.450088 0.450088)
			(layers "F.Cu" "F.Mask" "F.Paste")
			(net "GND")
		)
		(pad "BV33" smd circle
			(at -4.849876 11.700002 180)
			(size 0.450088 0.450088)
			(layers "F.Cu" "F.Mask" "F.Paste")
			(net "GND")
		)
		(pad "BV34" smd circle
			(at -3.910076 11.700002 180)
			(size 0.450088 0.450088)
			(layers "F.Cu" "F.Mask" "F.Paste")
			(net "GND")
		)
		(pad "BV35" smd circle
			(at -2.970022 11.700002 180)
			(size 0.450088 0.450088)
			(layers "F.Cu" "F.Mask" "F.Paste")
			(net "P5E_CPU0_P2_TX_DN<1>")
		)
		(pad "BV36" smd circle
			(at -2.029968 11.700002 180)
			(size 0.450088 0.450088)
			(layers "F.Cu" "F.Mask" "F.Paste")
			(net "P5E_CPU0_P2_TX_DP<1>")
		)
		(pad "BV37" smd circle
			(at -1.089914 11.700002 180)
			(size 0.450088 0.450088)
			(layers "F.Cu" "F.Mask" "F.Paste")
			(net "GND")
		)
		(pad "BV39" smd circle
			(at 0.78994 11.700002 180)
			(size 0.450088 0.450088)
			(layers "F.Cu" "F.Mask" "F.Paste")
			(net "GND")
		)
		(pad "BV40" smd circle
			(at 1.729994 11.700002 180)
			(size 0.450088 0.450088)
			(layers "F.Cu" "F.Mask" "F.Paste")
			(net "P5E_CPU0_P0_RX_DP<14>")
		)
	)
)
